FILE_TYPE = MULTI_PHYS_TABLE;

PART 'ME_DUMMY_SYMBOL'

{========================================================================================}
:VALUE                            | PART_TYPE | MATERIAL | PART_NUMBER           = STANDARD | LIFECYCLE | PART_NUMBER           | JEDEC_TYPE                       | DESCRIPTION                                       | MANUFTR | MANUF_PN      | RD_CMPLS_LVL | CMPLS_LVL | CLASS        | DIP_SMD | FROM_PJ        | DATA                      | FP_ECN                                      | EE_CHECK_LIST | PSL | PREFERENCE | CREATOR | CREATEDAY  | STATUS | ESD_CDM | ESD_HBM | ESD_MM | MSD | PIN_LENGTH_LONG_PIN | PIN_LENGTH_SHORT_PIN ;
{========================================================================================}
 'xlga3647_h3760x_left_p0'        | 'Mech'    | 'EMPTY'  | 'DUMMY37'(!)          = ''       | ''        | 'DUMMY37'             |'XLGA3647_H3760X_LEFT_P0'| 'xlga3647_h3760x_left_p0'                         | ''      | ''            | ''           | ''        | 'MECHANICAL' | ''      | ''             | ''                        | ''                                          | ''            | ''  | ''         | ''      | '20170104' | ''     | ''      | ''      | ''     | ''  | ''                  | ''                  
 'xlga3647_h3760x_right_p0'       | 'Mech'    | 'EMPTY'  | 'DUMMY38'(!)          = ''       | ''        | 'DUMMY38'             |'XLGA3647_H3760X_RIGHT_P0'| 'xlga3647_h3760x_right_p0'                        | ''      | ''            | ''           | ''        | 'MECHANICAL' | ''      | ''             | ''                        | ''                                          | ''            | ''  | ''         | ''      | '20170104' | ''     | ''      | ''      | ''     | ''  | ''                  | ''                  
 'CBS_3X558-8'                    | 'Mech'    | 'EMPTY'  | 'DUMMY47'(!)          = ''       | ''        | 'DUMMY47'             |'CBS_3X558-8'| 'CBS_3MMX558-8MM'                                 | ''      | ''            | ''           | ''        | 'MECHANICAL' | ''      | ''             | ''                        | ''                                          | ''            | ''  | ''         | ''      | '20170731' | ''     | ''      | ''      | ''     | ''  | ''                  | ''                  
 'PICKUP_SMDC20'                  | 'Mech'    | 'EMPTY'  | 'DUMMY48'(!)          = ''       | ''        | 'DUMMY48'             |'PICKUP_SMDC20'| 'PICKUP_SMDC20'                                   | ''      | ''            | ''           | ''        | 'MECHANICAL' | ''      | ''             | ''                        | ''                                          | ''            | ''  | ''         | ''      | '20170731' | ''     | ''      | ''      | ''     | ''  | ''                  | ''                  
 'PICKUP_SMDC10'                  | 'Mech'    | 'EMPTY'  | 'DUMMY49'(!)          = ''       | ''        | 'DUMMY49'             |'PICKUP_SMDC10'| 'PICKUP_SMDC10'                                   | ''      | ''            | ''           | ''        | 'MECHANICAL' | ''      | ''             | ''                        | ''                                          | ''            | ''  | ''         | ''      | '20170731' | ''     | ''      | ''      | ''     | ''  | ''                  | ''                  
 'MACLABEL_17X12'                 | 'Mech'    | 'EMPTY'  | 'DUMMY51'(!)          = ''       | ''        | 'DUMMY51'             |'MACLABEL_17X12'| 'MACLABEL_17X12'                                  | ''      | ''            | ''           | ''        | 'MECHANICAL' | ''      | ''             | ''                        | ''                                          | ''            | ''  | ''         | ''      | '20170920' | ''     | ''      | ''      | ''     | ''  | ''                  | ''                  
 'MSFTLABEL_27X6'                 | 'Mech'    | 'EMPTY'  | 'DUMMY52'(!)          = ''       | ''        | 'DUMMY52'             |'MSFTLABEL_27X6'| 'MSFTLABEL_27X6'                                  | ''      | ''            | ''           | ''        | 'MECHANICAL' | ''      | ''             | ''                        | ''                                          | ''            | ''  | ''         | ''      | '20170922' | ''     | ''      | ''      | ''     | ''  | ''                  | ''                  
 'xlga4189_j73622_left_p4'        | 'Mech'    | 'EMPTY'  | 'DUMMY53'(!)          = ''       | ''        | 'DUMMY53'             |'XLGA4189_J73622_LEFT_P4'| 'xlga4189_j73622_left_p4'                         | ''      | ''            | ''           | ''        | 'MECHANICAL' | ''      | ''             | ''                        | ''                                          | ''            | ''  | ''         | ''      | '20180116' | ''     | ''      | ''      | ''     | ''  | ''                  | ''                  
 'xlga4189_j73622_right_p4'       | 'Mech'    | 'EMPTY'  | 'DUMMY54'(!)          = ''       | ''        | 'DUMMY54'             |'XLGA4189_J73622_RIGHT_P4'| 'xlga4189_j73622_right_p4'                        | ''      | ''            | ''           | ''        | 'MECHANICAL' | ''      | ''             | ''                        | ''                                          | ''            | ''  | ''         | ''      | '20180116' | ''     | ''      | ''      | ''     | ''  | ''                  | ''                  
 'Alibaba Logo_16X14'             | 'Mech'    | 'EMPTY'  | 'DUMMY55'(!)          = ''       | ''        | 'DUMMY55'             |'ALIBABA_LOGO_16X14'| 'Alibaba Logo_16X14'                              | ''      | ''            | ''           | ''        | 'MECHANICAL' | ''      | ''             | ''                        | ''                                          | ''            | ''  | ''         | ''      | '20180201' | ''     | ''      | ''      | ''     | ''  | ''                  | ''                  
 'ELECTRICAL_HAZARD_LOGO'         | 'Mech'    | 'EMPTY'  | 'DUMMY56'(!)          = ''       | ''        | 'DUMMY56'             |'ELECTRICAL_HAZARD_LOGO'| 'ELECTRICAL_HAZARD_LOGO'                          | ''      | ''            | ''           | ''        | 'MECHANICAL' | ''      | ''             | ''                        | ''                                          | ''            | ''  | ''         | ''      | '20180323' | ''     | ''      | ''      | ''     | ''  | ''                  | ''                  
 'ELECTRICAL_HAZARD_LOGO_6-6X5-7' | 'Mech'    | 'EMPTY'  | 'DUMMY57'(!)          = ''       | ''        | 'DUMMY57'             |'ELECTRICAL_HAZARD_LOGO_6-6X5-7'| 'ELECTRICAL_HAZARD_LOGO_6-6X5-7'                  | ''      | ''            | ''           | ''        | 'MECHANICAL' | ''      | ''             | ''                        | ''                                          | ''            | ''  | ''         | ''      | '20180409' | ''     | ''      | ''      | ''     | ''  | ''                  | ''                  
 'QUANTA_LOGO_2X7-6'              | 'Mech'    | 'EMPTY'  | 'DUMMY58'(!)          = ''       | ''        | 'DUMMY58'             |'QUANTA_LOGO_2X7-6'| 'QUANTA_LOGO_2X7-6'                               | ''      | ''            | ''           | ''        | 'MECHANICAL' | ''      | ''             | ''                        | ''                                          | ''            | ''  | ''         | ''      | '20180424' | ''     | ''      | ''      | ''     | ''  | ''                  | ''                  
 'NOKIA_LOGO_12-7X2-1'            | 'Mech'    | 'EMPTY'  | 'DUMMY59'(!)          = ''       | ''        | 'DUMMY59'             |'NOKIA_LOGO_12-7X2-1'| 'NOKIA_LOGO_12-7X2-1'                             | ''      | ''            | ''           | ''        | 'MECHANICAL' | ''      | ''             | ''                        | ''                                          | ''            | ''  | ''         | ''      | '20180629' | ''     | ''      | ''      | ''     | ''  | ''                  | ''                  
 'NOKIA_LOGO_20X3-3'              | 'Mech'    | 'EMPTY'  | 'DUMMY60'(!)          = ''       | ''        | 'DUMMY60'             |'NOKIA_LOGO_20X3-3'| 'NOKIA_LOGO_20X3-3'                               | ''      | ''            | ''           | ''        | 'MECHANICAL' | ''      | ''             | ''                        | ''                                          | ''            | ''  | ''         | ''      | '20180629' | ''     | ''      | ''      | ''     | ''  | ''                  | ''                  
 'xlga4189_j73622_left_p5'        | 'Mech'    | 'EMPTY'  | 'DUMMY61'(!)          = ''       | ''        | 'DUMMY61'             |'XLGA4189_J73622_LEFT_P5'| 'xlga4189_j73622_left_p5(SOCKET4189S_82X62XA)'    | ''      | ''            | ''           | ''        | 'MECHANICAL' | ''      | ''             | ''                        | ''                                          | ''            | ''  | ''         | ''      | '20190306' | ''     | ''      | ''      | ''     | ''  | ''                  | ''                  
 'xlga4189_j73622_right_p5'       | 'Mech'    | 'EMPTY'  | 'DUMMY62'(!)          = ''       | ''        | 'DUMMY62'             |'XLGA4189_J73622_RIGHT_P5'| 'xlga4189_j73622_right_p5(SOCKET4189S_82X62XA)'   | ''      | ''            | ''           | ''        | 'MECHANICAL' | ''      | ''             | ''                        | ''                                          | ''            | ''  | ''         | ''      | '20190306' | ''     | ''      | ''      | ''     | ''  | ''                  | ''                  
 'PICKUP_SMDC30'                  | 'Mech'    | 'EMPTY'  | 'DUMMY63'(!)          = ''       | ''        | 'DUMMY63'             |'PICKUP_SMDC30'| 'PICKUP_SMDC30'                                   | ''      | ''            | ''           | ''        | 'MECHANICAL' | ''      | ''             | ''                        | ''                                          | ''            | ''  | ''         | ''      | '20190717' | ''     | ''      | ''      | ''     | ''  | ''                  | ''                  
 'TENCENT_LOGO_12-05X2-25'        | 'Mech'    | 'EMPTY'  | 'DUMMY65'(!)          = ''       | ''        | 'DUMMY65'             |'TENCENT_LOGO_12-05X2-25'| 'TENCENT_LOGO_12-05X2-25'                         | ''      | ''            | ''           | ''        | 'MECHANICAL' | ''      | ''             | ''                        | ''                                          | ''            | ''  | ''         | ''      | '20191007' | ''     | ''      | ''      | ''     | ''  | ''                  | ''                  
 'TENCENT_LOGO_38-16X7-23'        | 'Mech'    | 'EMPTY'  | 'DUMMY66'(!)          = ''       | ''        | 'DUMMY66'             |'TENCENT_LOGO_38-16X7-23'| 'TENCENT_LOGO_38-16X7-23'                         | ''      | ''            | ''           | ''        | 'MECHANICAL' | ''      | ''             | ''                        | ''                                          | ''            | ''  | ''         | ''      | '20191015' | ''     | ''      | ''      | ''     | ''  | ''                  | ''                  
 'MACLABEL_32-75X7-35'            | 'Mech'    | 'EMPTY'  | 'DUMMY67'(!)          = ''       | ''        | 'DUMMY67'             |'MACLABEL_32-75X7-35'| 'MACLABEL_32-75X7-35'                             | ''      | ''            | ''           | ''        | 'MECHANICAL' | ''      | ''             | ''                        | ''                                          | ''            | ''  | ''         | ''      | '20200504' | ''     | ''      | ''      | ''     | ''  | ''                  | ''                  
 'BMCLABEL_12X15'                 | 'Mech'    | 'EMPTY'  | 'DUMMY68'(!)          = ''       | ''        | 'DUMMY68'             |'BMCLABEL_12X15'| 'BMCLABEL_12X15'                                  | ''      | ''            | ''           | ''        | 'MECHANICAL' | ''      | ''             | ''                        | ''                                          | ''            | ''  | ''         | ''      | '20200504' | ''     | ''      | ''      | ''     | ''  | ''                  | ''                  
 'SNLABEL_7X7'                    | 'Mech'    | 'EMPTY'  | 'DUMMY69'(!)          = ''       | ''        | 'DUMMY69'             |'SNLABEL_7X7'| 'SNLABEL_7X7'                                     | ''      | ''            | ''           | ''        | 'MECHANICAL' | ''      | ''             | ''                        | ''                                          | ''            | ''  | ''         | ''      | '20200526' | ''     | ''      | ''      | ''     | ''  | ''                  | ''                  
 'PNLABEL_23-5X5'                 | 'Mech'    | 'EMPTY'  | 'DUMMY70'(!)          = ''       | ''        | 'DUMMY70'             |'PNLABEL_23-5X5'| 'PNLABEL_23-5X5'                                  | ''      | ''            | ''           | ''        | 'MECHANICAL' | ''      | ''             | ''                        | ''                                          | ''            | ''  | ''         | ''      | '20200526' | ''     | ''      | ''      | ''     | ''  | ''                  | ''                  
 'REWORKLABEL_39-5X6-5'           | 'Mech'    | 'EMPTY'  | 'DUMMY71'(!)          = ''       | ''        | 'DUMMY71'             |'REWORKLABEL_39-5X6-5'| 'REWORKLABEL_39-5X6-5'                            | ''      | ''            | ''           | ''        | 'MECHANICAL' | ''      | ''             | ''                        | ''                                          | ''            | ''  | ''         | ''      | '20200826' | ''     | ''      | ''      | ''     | ''  | ''                  | ''                  
 'QUANTA_LOGO_7X26'               | 'Mech'    | 'EMPTY'  | 'DUMMY1'(!)           = ''       | ''        | 'DUMMY1'              |'QUANTA_LOGO_7X26'| 'QUANTA_LOGO_7X26'                                | ''      | ''            | ''           | ''        | 'MECHANICAL' | ''      | ''             | ''                        | ''                                          | ''            | ''  | ''         | ''      | '20141104' | ''     | ''      | ''      | ''     | ''  | ''                  | ''                  
 'WEEE'                           | 'Mech'    | 'EMPTY'  | 'DUMMY2'(!)           = ''       | ''        | 'DUMMY2'              |'WEEE'| 'WEEE'                                            | ''      | ''            | ''           | ''        | 'MECHANICAL' | ''      | ''             | ''                        | ''                                          | ''            | ''  | ''         | ''      | '20141104' | ''     | ''      | ''      | ''     | ''  | ''                  | ''                  
 'BIOS-BMCLABEL_10-5X10-5'        | 'Mech'    | 'EMPTY'  | 'DUMMY5'(!)           = ''       | ''        | 'DUMMY5'              |'BIOS-BMCLABEL_10-5X10-5'| 'BIOS-BMCLABEL_10-5X10-5'                         | ''      | ''            | ''           | ''        | 'MECHANICAL' | ''      | ''             | ''                        | ''                                          | ''            | ''  | ''         | ''      | '20141104' | ''     | ''      | ''      | ''     | ''  | ''                  | ''                  
 'Legacy BIOS Label'              | 'Mech'    | 'EMPTY'  | 'DUMMY27_AP0SERVER05'(!) = ''       | ''        | 'DUMMY27_AP0SERVER05' |'BIOS-BMCLABEL_10-5X10-5'| 'BIOS LICENCE AMI SERVER BIOS LABEL'              | ''      | ''            | ''           | ''        | 'MECHANICAL' | ''      | ''             | ''                        | ''                                          | ''            | ''  | ''         | ''      | '20160105' | ''     | ''      | ''      | ''     | ''  | ''                  | ''                  
 'EFI BIOS Label'                 | 'Mech'    | 'EMPTY'  | 'DUMMY28_HCLU2002010'(!) = ''       | ''        | 'DUMMY28_HCLU2002010' |'BIOS-BMCLABEL_10-5X10-5'| 'EFI BIOS LABEL LU2(HCLU2002,REV3A)'              | ''      | ''            | ''           | ''        | 'MECHANICAL' | ''      | ''             | ''                        | ''                                          | ''            | ''  | ''         | ''      | '20160105' | ''     | ''      | ''      | ''     | ''  | ''                  | ''                  
 'xlga4189_j73622_left_p4'        | 'Mech'    | 'MECH'   | 'DGA^0000070'(!)      = ''       | ''        | 'DGA^0000070'         |'XLGA4189_J73622_LEFT_P4'| 'SOCKET 2097P P4-LSA LGA(P0.8585,H7.75)'          | 'TYC'   | '1-2324271-4' | 'EP(V1)'     | 'EP(V1)'  | 'MECHANICAL' | ''      | 'S6YQ-COOPER'  | ''                        | ''                                          | ''            | ''  | ''         | ''      | '20210917' | ''     | ''      | ''      | ''     | ''  | ''                  | ''                  
 'xlga4189_j73622_left_p4'        | 'Mech'    | 'EMPTY'  | 'DGA^0000070'(!)      = ''       | ''        | 'DGA^0000070'         |'XLGA4189_J73622_LEFT_P4'| 'SOCKET 2097P P4-LSA LGA(P0.8585,H7.75)'          | 'TYC'   | '1-2324271-4' | 'EP(V1)'     | 'EP(V1)'  | 'MECHANICAL' | ''      | 'S6YQ-COOPER'  | ''                        | ''                                          | ''            | ''  | ''         | ''      | '20210917' | ''     | ''      | ''      | ''     | ''  | ''                  | ''                  
 'xlga4189_j73622_right_p4'       | 'Mech'    | 'MECH'   | 'DGA^0000069'(!)      = ''       | ''        | 'DGA^0000069'         |'XLGA4189_J73622_RIGHT_P4'| 'SOCKET 2092P P4-RSA LGA(P0.8585,H7.75)'          | 'TYC'   | '1-2324271-3' | 'EP(V1)'     | 'EP(V1)'  | 'MECHANICAL' | ''      | 'S6YQ-COOPER'  | ''                        | ''                                          | ''            | ''  | ''         | ''      | '20210917' | ''     | ''      | ''      | ''     | ''  | ''                  | ''                  
 'xlga4189_j73622_right_p4'       | 'Mech'    | 'EMPTY'  | 'DGA^0000069'(!)      = ''       | ''        | 'DGA^0000069'         |'XLGA4189_J73622_RIGHT_P4'| 'SOCKET 2092P P4-RSA LGA(P0.8585,H7.75)'          | 'TYC'   | '1-2324271-3' | 'EP(V1)'     | 'EP(V1)'  | 'MECHANICAL' | ''      | 'S6YQ-COOPER'  | ''                        | ''                                          | ''            | ''  | ''         | ''      | '20210917' | ''     | ''      | ''      | ''     | ''  | ''                  | ''                  
 'PB-E1_SMALL'                    | 'Mech'    | 'EMPTY'  | 'DUMMY3'(!)           = ''       | ''        | 'DUMMY3'              |'PB-E1_SMALL'| 'PB-E1_SMALL'                                     | ''      | ''            | ''           | ''        | 'MECHANICAL' | ''      | ''             | ''                        | ''                                          | ''            | ''  | ''         | ''      | '20210923' | ''     | ''      | ''      | ''     | ''  | ''                  | ''                  
 'PCBA_LABEL_15X5'                | 'Mech'    | 'EMPTY'  | 'DUMMY4'(!)           = ''       | ''        | 'DUMMY4'              |'PNLABEL_15X5'| 'PCBA_LABEL_15X5'                                 | ''      | ''            | ''           | ''        | 'MECHANICAL' | ''      | ''             | ''                        | ''                                          | ''            | ''  | ''         | ''      | '20210923' | ''     | ''      | ''      | ''     | ''  | ''                  | ''                  
 'BARCODE'                        | 'Mech'    | 'EMPTY'  | 'DUMMY6'(!)           = ''       | ''        | 'DUMMY6'              |'BARCODE'| 'SERIEL_LABEL'                                    | ''      | ''            | ''           | ''        | 'MECHANICAL' | ''      | ''             | ''                        | ''                                          | ''            | ''  | ''         | ''      | '20210923' | ''     | ''      | ''      | ''     | ''  | ''                  | ''                  
 'PCB_VENDOR_LOGO_15X8'           | 'Mech'    | 'EMPTY'  | 'DUMMY7'(!)           = ''       | ''        | 'DUMMY7'              |'PCB_VENDOR_LOGO_15X8'| 'PCB_VENDOR_LOGO_15X8'                            | ''      | ''            | ''           | ''        | 'MECHANICAL' | ''      | ''             | ''                        | ''                                          | ''            | ''  | ''         | ''      | '20210923' | ''     | ''      | ''      | ''     | ''  | ''                  | ''                  
 'QCT_LOGO_12X12'                 | 'Mech'    | 'EMPTY'  | 'DUMMY13'(!)          = ''       | ''        | 'DUMMY13'             |'QCT_LOGO_12X12'| 'QCT_LOGO_12X12'                                  | ''      | ''            | ''           | ''        | 'MECHANICAL' | ''      | ''             | ''                        | ''                                          | ''            | ''  | ''         | ''      | '20210923' | ''     | ''      | ''      | ''     | ''  | ''                  | ''                  
 'BARCODE_25X6'                   | 'Mech'    | 'EMPTY'  | 'DUMMY14'(!)          = ''       | ''        | 'DUMMY14'             |'BARCODE_25X6'| 'BARCODE_25X6'                                    | ''      | ''            | ''           | ''        | 'MECHANICAL' | ''      | 'S2SP-CHRIS'   | ''                        | ''                                          | ''            | ''  | ''         | ''      | '20210923' | ''     | ''      | ''      | ''     | ''  | ''                  | ''                  
 'BARCODE_20X6'                   | 'Mech'    | 'EMPTY'  | 'DUMMY15'(!)          = ''       | ''        | 'DUMMY15'             |'BARCODE_20X6'| 'BARCODE_20X6'                                    | ''      | ''            | ''           | ''        | 'MECHANICAL' | ''      | 'UH3-JACK'     | ''                        | ''                                          | ''            | ''  | ''         | ''      | '20210923' | ''     | ''      | ''      | ''     | ''  | ''                  | ''                  
 'CE_LOGO_5.8X5.08'               | 'Mech'    | 'EMPTY'  | 'DUMMY18'(!)          = ''       | ''        | 'DUMMY18'             |'CE'| 'CE LOGO_5.842X5.08'                              | ''      | ''            | ''           | ''        | 'MECHANICAL' | ''      | 'T6MG-RAYMOND' | 'Safety EMC logo.xlsx'    | ''                                          | ''            | ''  | ''         | ''      | '20210923' | ''     | ''      | ''      | ''     | ''  | ''                  | ''                  
 'CE_LOGO_11.5X10.2'              | 'Mech'    | 'EMPTY'  | 'DUMMY19'(!)          = ''       | ''        | 'DUMMY19'             |'CE_Q'| 'CE_LOGO_11.481X10.185'                           | ''      | ''            | ''           | ''        | 'MECHANICAL' | ''      | 'T6MG-RAYMOND' | 'Safety EMC logo.xlsx'    | ''                                          | ''            | ''  | ''         | ''      | '20210923' | ''     | ''      | ''      | ''     | ''  | ''                  | ''                  
 'CE_LOGO_4.8X4'                  | 'Mech'    | 'EMPTY'  | 'DUMMY20'(!)          = ''       | ''        | 'DUMMY20'             |'CE_5X4'| 'CE_LOGO_4.826X4.064'                             | ''      | ''            | ''           | ''        | 'MECHANICAL' | ''      | 'T6MG-RAYMOND' | 'Safety EMC logo.xlsx'    | ''                                          | ''            | ''  | ''         | ''      | '20210923' | ''     | ''      | ''      | ''     | ''  | ''                  | ''                  
 'RCM_LOGO'                       | 'Mech'    | 'EMPTY'  | 'DUMMY21'(!)          = ''       | ''        | 'DUMMY21'             |'RCM'| 'RCM_LOGO'                                        | ''      | ''            | ''           | ''        | 'MECHANICAL' | ''      | 'T6MG-RAYMOND' | 'Safety EMC logo.xlsx'    | ''                                          | ''            | ''  | ''         | ''      | '20210923' | ''     | ''      | ''      | ''     | ''  | ''                  | ''                  
 'KCCA_LOGO'                      | 'Mech'    | 'EMPTY'  | 'DUMMY22'(!)          = ''       | ''        | 'DUMMY22'             |'KCCA'| 'KCCA_LOGO'                                       | ''      | ''            | ''           | ''        | 'MECHANICAL' | ''      | 'T6MG-RAYMOND' | 'Safety EMC logo.xlsx'    | ''                                          | ''            | ''  | ''         | ''      | '20210923' | ''     | ''      | ''      | ''     | ''  | ''                  | ''                  
 'SNLABEL_20X6'                   | 'Mech'    | 'EMPTY'  | 'DUMMY25'(!)          = ''       | ''        | 'DUMMY25'             |'SNLABEL_20X6'| 'SNLABEL_20X6'                                    | ''      | ''            | ''           | ''        | 'MECHANICAL' | ''      | 'JSA-DENNY'    | ''                        | ''                                          | ''            | ''  | ''         | ''      | '20210923' | ''     | ''      | ''      | ''     | ''  | ''                  | ''                  
 'SNLABEL_31-75X6-35'             | 'Mech'    | 'EMPTY'  | 'DUMMY26'(!)          = ''       | ''        | 'DUMMY26'             |'SNLABEL_31-75X6-35'| 'SNLABEL_31-75X6-35_SEL'                          | ''      | ''            | ''           | ''        | 'MECHANICAL' | ''      | 'T2H-GAVEN'    | 'SNLABEL_31-75X6-35.pdf'  | 'SNLABEL_31-75X6-35.pdf'                    | ''            | ''  | ''         | ''      | '20210923' | ''     | ''      | ''      | ''     | ''  | ''                  | ''                  
 'GPNLABEL_31-75X6-35'            | 'Mech'    | 'EMPTY'  | 'DUMMY29'(!)          = ''       | ''        | 'DUMMY29'             |'GPNLABEL_31-75X6-35'| 'GPNLABEL_31-75X6-35_SEL'                         | ''      | ''            | ''           | ''        | 'MECHANICAL' | ''      | 'T2H-WADE'     | 'GPNLABEL_31-75X6-35.pdf' | ''                                          | ''            | ''  | ''         | ''      | '20210923' | ''     | ''      | ''      | ''     | ''  | ''                  | ''                  
 'UL_LOGO_E142692_7.3X4.4'        | 'Mech'    | 'EMPTY'  | 'DUMMY30'(!)          = ''       | ''        | 'DUMMY30'             |'UL_E142692'| 'UL_LOGO_E142692_7.3X4.4(UL File number E142692)' | ''      | ''            | ''           | ''        | 'MECHANICAL' | ''      | 'F20-OWEN'     | ''                        | 'UL_LOGO_E142692_7.3X4.4.pdf'               | ''            | ''  | ''         | ''      | '20210923' | ''     | ''      | ''      | ''     | ''  | ''                  | ''                  
 'FCC_LOGO'                       | 'Mech'    | 'EMPTY'  | 'DUMMY31'(!)          = ''       | ''        | 'DUMMY31'             |'FCC'| 'FCC_LOGO_11.2X7.9'                               | ''      | ''            | ''           | ''        | 'MECHANICAL' | ''      | ''             | ''                        | ''                                          | ''            | ''  | ''         | ''      | '20210923' | ''     | ''      | ''      | ''     | ''  | ''                  | ''                  
 'BARCODE_40X6'                   | 'Mech'    | 'EMPTY'  | 'DUMMY32'(!)          = ''       | ''        | 'DUMMY32'             |'BARCODE_40X6'| 'BARCODE_40X6'                                    | ''      | ''            | ''           | ''        | 'MECHANICAL' | ''      | 'S5D-THOMAS'   | ''                        | ''                                          | ''            | ''  | ''         | ''      | '20210923' | ''     | ''      | ''      | ''     | ''  | ''                  | ''                  
 'BARCODE_15X5'                   | 'Mech'    | 'EMPTY'  | 'DUMMY34'(!)          = ''       | ''        | 'DUMMY34'             |'BARCODE_15X5'| 'BARCODE_15X5'                                    | ''      | ''            | ''           | ''        | 'MECHANICAL' | ''      | 'A5W-MARCUS'   | ''                        | 'BARCODE_15X5.msg'                          | ''            | ''  | ''         | ''      | '20210923' | ''     | ''      | ''      | ''     | ''  | ''                  | ''                  
 'SNLABEL_50-8X6-35'              | 'Mech'    | 'EMPTY'  | 'DUMMY35'(!)          = ''       | ''        | 'DUMMY35'             |'SNLABEL_50-8X6-35'| 'SNLABEL_50-8X6-35'                               | ''      | ''            | ''           | ''        | 'MECHANICAL' | ''      | 'STUDY-CANDY'  | ''                        | 'SNLABEL_50-8X6-35 & SNLABEL_15X5.msg'      | ''            | ''  | ''         | ''      | '20210923' | ''     | ''      | ''      | ''     | ''  | ''                  | ''                  
 'SNLABEL_15X5'                   | 'Mech'    | 'EMPTY'  | 'DUMMY36'(!)          = ''       | ''        | 'DUMMY36'             |'SNLABEL_15X5'| 'SNLABEL_15X5'                                    | ''      | ''            | ''           | ''        | 'MECHANICAL' | ''      | 'STUDY-CANDY'  | ''                        | 'SNLABEL_50-8X6-35 & SNLABEL_15X5.msg'      | ''            | ''  | ''         | ''      | '20210923' | ''     | ''      | ''      | ''     | ''  | ''                  | ''                  
 'MICROSOFT_LOGO_7X33'            | 'Mech'    | 'EMPTY'  | 'DUMMY40'(!)          = ''       | ''        | 'DUMMY40'             |'MICROSOFT_LOGO_7X33'| 'MICROSOFT_LOGO_7X33'                             | ''      | ''            | ''           | ''        | 'MECHANICAL' | ''      | 'T6U-JH'       | ''                        | ''                                          | ''            | ''  | ''         | ''      | '20210923' | ''     | ''      | ''      | ''     | ''  | ''                  | ''                  
 'PNLABEL_19-5X8'                 | 'Mech'    | 'EMPTY'  | 'DUMMY41'(!)          = ''       | ''        | 'DUMMY41'             |'PNLABEL_19-5X8'| 'PNLABEL_19-5X8'                                  | ''      | ''            | ''           | ''        | 'MECHANICAL' | ''      | 'F0A-BERNIE'   | ''                        | ''                                          | ''            | ''  | ''         | ''      | '20210923' | ''     | ''      | ''      | ''     | ''  | ''                  | ''                  
 'BARCODE_49-5X8-35'              | 'Mech'    | 'EMPTY'  | 'DUMMY42'(!)          = ''       | ''        | 'DUMMY42'             |'BARCODE_49-5X8-35'| 'BARCODE_49-5X8-35'                               | ''      | ''            | ''           | ''        | 'MECHANICAL' | ''      | 'F0A-BERNIE'   | ''                        | ''                                          | ''            | ''  | ''         | ''      | '20210923' | ''     | ''      | ''      | ''     | ''  | ''                  | ''                  
 'BARCODE_27X8'                   | 'Mech'    | 'EMPTY'  | 'DUMMY43'(!)          = ''       | ''        | 'DUMMY43'             |'BARCODE_27X8'| 'BARCODE_27X8'                                    | ''      | ''            | ''           | ''        | 'MECHANICAL' | ''      | 'F0A-BERNIE'   | ''                        | ''                                          | ''            | ''  | ''         | ''      | '20210923' | ''     | ''      | ''      | ''     | ''  | ''                  | ''                  
 'SNLABEL_47-5X6-35'              | 'Mech'    | 'EMPTY'  | 'DUMMY44'(!)          = ''       | ''        | 'DUMMY44'             |'SNLABEL_47-5X6-35'| 'SNLABEL_47-5X6-35'                               | ''      | ''            | ''           | ''        | 'MECHANICAL' | ''      | ''             | ''                        | 'FW DFx of the PCB and PCBA Discussion.msg' | ''            | ''  | ''         | ''      | '20210923' | ''     | ''      | ''      | ''     | ''  | ''                  | ''                  
 'SNLABEL_17-5X6'                 | 'Mech'    | 'EMPTY'  | 'DUMMY45'(!)          = ''       | ''        | 'DUMMY45'             |'SNLABEL_17-5X6'| 'SNLABEL_17-5X6'                                  | ''      | ''            | ''           | ''        | 'MECHANICAL' | ''      | ''             | ''                        | 'FW DFx of the PCB and PCBA Discussion.msg' | ''            | ''  | ''         | ''      | '20210923' | ''     | ''      | ''      | ''     | ''  | ''                  | ''                  
 'SNLABEL_27X6'                   | 'Mech'    | 'EMPTY'  | 'DUMMY46'(!)          = ''       | ''        | 'DUMMY46'             |'SNLABEL_27X6'| 'SNLABEL_27X6'                                    | ''      | ''            | ''           | ''        | 'MECHANICAL' | ''      | ''             | ''                        | 'FW DFx of the PCB and PCBA Discussion.msg' | ''            | ''  | ''         | ''      | '20210923' | ''     | ''      | ''      | ''     | ''  | ''                  | ''                  
 'SNLABEL_31-8X6-35'              | 'Mech'    | 'EMPTY'  | 'DUMMY73'(!)          = ''       | ''        | 'DUMMY73'             |'SNLABEL_31-8X6-35'| 'SNLABEL_31-8X6-35'                               | ''      | ''            | ''           | ''        | 'MECHANICAL' | ''      | 'T6G-JOHN'     | ''                        | ''                                          | ''            | ''  | ''         | ''      | '20211013' | ''     | ''      | ''      | ''     | ''  | ''                  | ''                  
 'SNLABEL_10X6'                   | 'Mech'    | 'EMPTY'  | 'DUMMY74'(!)          = ''       | ''        | 'DUMMY74'             |'SNLABEL_10X6'| 'SNLABEL_10X6'                                    | ''      | ''            | ''           | ''        | 'MECHANICAL' | ''      | 'F0T-IVES'     | ''                        | ''                                          | ''            | ''  | ''         | ''      | '20220505' | ''     | ''      | ''      | ''     | ''  | ''                  | ''                  
 'G_PCB_VENDOR_LOGO_15X8'         | 'Mech'    | 'EMPTY'  | 'SP_DUMMY7'(!)        = ''       | ''        | 'DUMMY7'              |'G_PCB_VENDOR_LOGO_15X8'| 'G_PCB_VENDOR_LOGO_15X8 (FOR SEL)'                | ''      | ''            | ''           | ''        | 'MECHANICAL' | ''      | ''             | ''                        | ''                                          | ''            | ''  | ''         | ''      | '20221125' | ''     | ''      | ''      | ''     | ''  | ''                  | ''                  

END_PART

END.

